(kicad_pcb
	(version 20260206)
	(generator "pcbnew")
	(generator_version "10.0")
	(general
		(thickness 1.6)
		(legacy_teardrops no)
	)
	(paper "A4")
	(title_block
		(title "Wiwynn_Tioga_Pass_MB.brd")
		(comment 1 "Tioga Pass / footprints 94-101 of 4770")
	)
	(layers
		(0 "F.Cu" signal "TOP")
		(4 "In1.Cu" signal "L2GND")
		(6 "In2.Cu" signal "L3")
		(8 "In3.Cu" signal "L4GND")
		(10 "In4.Cu" signal "L5")
		(12 "In5.Cu" signal "L6GND")
		(14 "In6.Cu" signal "L7VCC")
		(16 "In7.Cu" signal "L8VCC")
		(18 "In8.Cu" signal "L9GND")
		(20 "In9.Cu" signal "L10")
		(22 "In10.Cu" signal "L11GND")
		(24 "In11.Cu" signal "L12")
		(26 "In12.Cu" signal "L13GND")
		(2 "B.Cu" signal "BOTTOM")
		(9 "F.Adhes" user "F.Adhesive")
		(11 "B.Adhes" user "B.Adhesive")
		(13 "F.Paste" user "Package Geometry/Pastemask Top")
		(15 "B.Paste" user "Package Geometry/Pastemask Bottom")
		(5 "F.SilkS" user "Ref Des/Silkscreen Top")
		(7 "B.SilkS" user "Ref Des/Silkscreen Bottom")
		(1 "F.Mask" user "Board Geometry/Soldermask Top")
		(3 "B.Mask" user "Board Geometry/Soldermask Bottom")
		(17 "Dwgs.User" user "User.Drawings")
		(19 "Cmts.User" user "User.Comments")
		(21 "Eco1.User" user "User.Eco1")
		(23 "Eco2.User" user "User.Eco2")
		(25 "Edge.Cuts" user "Board Geometry/Outline")
		(27 "Margin" user)
		(31 "F.CrtYd" user "Package Geometry/Place Bound Top")
		(29 "B.CrtYd" user "Package Geometry/Place Bound Bottom")
		(35 "F.Fab" user "Ref Des/Assembly Top")
		(33 "B.Fab" user "Ref Des/Assembly Bottom")
	)
	(footprint ""
		(layer "F.Cu")
		(at 153.4922 -149.606 -90)
		(property "Reference" "C3A3"
			(at 0 0 270)
			(layer "F.SilkS")
			(hide yes)
			(effects
				(font
					(size 1.27 1.27)
				)
			)
		)
		(property "Value" ""
			(at 0 0 270)
			(layer "F.Fab")
			(effects
				(font
					(size 1.27 1.27)
				)
			)
		)
		(duplicate_pad_numbers_are_jumpers no)
		(fp_rect
			(start -0.4953 1.6002)
			(end 0.4953 -0.2032)
			(stroke
				(width 0)
				(type default)
			)
			(fill no)
			(layer "F.CrtYd")
		)
		(fp_line
			(start -0.4953 1.6002)
			(end -0.4953 -0.2032)
			(stroke
				(width 0.1)
				(type default)
			)
			(layer "F.Fab")
		)
		(fp_line
			(start 0.4953 1.6002)
			(end -0.4953 1.6002)
			(stroke
				(width 0.1)
				(type default)
			)
			(layer "F.Fab")
		)
		(fp_line
			(start -0.4953 -0.2032)
			(end 0.4953 -0.2032)
			(stroke
				(width 0.1)
				(type default)
			)
			(layer "F.Fab")
		)
		(fp_line
			(start 0.4953 -0.2032)
			(end 0.4953 1.6002)
			(stroke
				(width 0.1)
				(type default)
			)
			(layer "F.Fab")
		)
		(pad "1" smd rect
			(at 0 0 270)
			(size 0.762 0.889)
			(layers "F.Cu" "F.Mask" "F.Paste")
			(net "PVPP_KLM")
		)
		(pad "2" smd rect
			(at 0 1.397 270)
			(size 0.762 0.889)
			(layers "F.Cu" "F.Mask" "F.Paste")
			(net "GND")
		)
		(zone
			(layer "F.Cu")
			(hatch none 0.5)
			(connect_pads
				(clearance 0)
			)
			(min_thickness 0.25)
			(keepout
				(tracks not_allowed)
				(vias allowed)
				(pads allowed)
				(copperpour not_allowed)
				(footprints allowed)
			)
			(placement
				(enabled no)
				(sheetname "")
			)
			(fill
				(thermal_gap 0.5)
				(thermal_bridge_width 0.5)
				(island_removal_mode 0)
			)
			(polygon
				(pts
					(xy 152.5397 -149.987) (xy 152.5397 -149.225) (xy 153.0477 -149.225) (xy 153.0477 -149.987)
				)
			)
		)
	)
	(footprint ""
		(layer "F.Cu")
		(at 407.40076 -57.79389)
		(property "Reference" "C8E7"
			(at 0 0 0)
			(layer "F.SilkS")
			(hide yes)
			(effects
				(font
					(size 1.27 1.27)
				)
			)
		)
		(property "Value" "*"
			(at -0.0762 -6.2357 0)
			(unlocked yes)
			(layer "F.Fab")
			(hide yes)
			(effects
				(font
					(size 1.27 1.016)
					(thickness 0.1524)
				)
			)
		)
		(property "Device Type" "SC22U16V5MX-4-GP_SMD-BCG5-SC22A"
			(at -0.0762 -8.2677 0)
			(unlocked yes)
			(layer "F.Fab")
			(hide yes)
			(effects
				(font
					(size 1.27 1.016)
					(thickness 0.1524)
				)
			)
		)
		(duplicate_pad_numbers_are_jumpers no)
		(fp_line
			(start 0.635 0)
			(end -0.635 0)
			(stroke
				(width 0.508)
				(type default)
			)
			(layer "F.SilkS")
		)
		(fp_rect
			(start -0.9652 1.778)
			(end 0.9652 -1.778)
			(stroke
				(width 0)
				(type default)
			)
			(fill no)
			(layer "F.CrtYd")
		)
		(fp_poly
			(pts
				(xy -0.9652 -1.778) (xy 0.9652 -1.778) (xy 0.9652 1.778) (xy -0.9652 1.778)
			)
			(stroke
				(width 0)
				(type default)
			)
			(fill no)
			(layer "F.Fab")
		)
		(pad "1" smd rect
			(at 0 -0.9652)
			(size 1.397 1.143)
			(layers "F.Cu" "F.Mask" "F.Paste")
			(net "P5V_STBY")
		)
		(pad "2" smd rect
			(at 0 0.9652)
			(size 1.397 1.143)
			(layers "F.Cu" "F.Mask" "F.Paste")
			(net "GND")
		)
	)
	(footprint ""
		(layer "F.Cu")
		(at 406.0825 -50.038 90)
		(property "Reference" "R8D27"
			(at 0 0 90)
			(layer "F.SilkS")
			(hide yes)
			(effects
				(font
					(size 1.27 1.27)
				)
			)
		)
		(property "Value" ""
			(at 0 0 90)
			(layer "F.Fab")
			(effects
				(font
					(size 1.27 1.27)
				)
			)
		)
		(duplicate_pad_numbers_are_jumpers no)
		(fp_poly
			(pts
				(xy -0.2794 -0.1016) (xy 0.2794 -0.1016) (xy 0.2794 0.9906) (xy -0.2794 0.9906)
			)
			(stroke
				(width 0)
				(type default)
			)
			(fill no)
			(layer "F.CrtYd")
		)
		(fp_line
			(start 0.2794 -0.1016)
			(end -0.2794 -0.1016)
			(stroke
				(width 0.1)
				(type default)
			)
			(layer "F.Fab")
		)
		(fp_line
			(start -0.2794 -0.1016)
			(end -0.2794 0.9906)
			(stroke
				(width 0.1)
				(type default)
			)
			(layer "F.Fab")
		)
		(fp_line
			(start 0.2794 0.9906)
			(end 0.2794 -0.1016)
			(stroke
				(width 0.1)
				(type default)
			)
			(layer "F.Fab")
		)
		(fp_line
			(start -0.2794 0.9906)
			(end 0.2794 0.9906)
			(stroke
				(width 0.1)
				(type default)
			)
			(layer "F.Fab")
		)
		(pad "1" smd rect
			(at 0 0 90)
			(size 0.508 0.508)
			(layers "F.Cu" "F.Mask" "F.Paste")
			(net "PD_FRU_WP")
		)
		(pad "2" smd rect
			(at 0 0.889 90)
			(size 0.508 0.508)
			(layers "F.Cu" "F.Mask" "F.Paste")
			(net "GND")
		)
		(zone
			(layer "F.Cu")
			(hatch none 0.5)
			(connect_pads
				(clearance 0)
			)
			(min_thickness 0.25)
			(keepout
				(tracks allowed)
				(vias not_allowed)
				(pads allowed)
				(copperpour not_allowed)
				(footprints allowed)
			)
			(placement
				(enabled no)
				(sheetname "")
			)
			(fill
				(thermal_gap 0.5)
				(thermal_bridge_width 0.5)
				(island_removal_mode 0)
			)
			(polygon
				(pts
					(xy 406.3365 -49.784) (xy 406.3365 -50.292) (xy 406.7175 -50.292) (xy 406.7175 -49.784)
				)
			)
		)
		(zone
			(layer "F.Cu")
			(hatch none 0.5)
			(connect_pads
				(clearance 0)
			)
			(min_thickness 0.25)
			(keepout
				(tracks not_allowed)
				(vias allowed)
				(pads allowed)
				(copperpour not_allowed)
				(footprints allowed)
			)
			(placement
				(enabled no)
				(sheetname "")
			)
			(fill
				(thermal_gap 0.5)
				(thermal_bridge_width 0.5)
				(island_removal_mode 0)
			)
			(polygon
				(pts
					(xy 406.7175 -49.784) (xy 406.7175 -50.292) (xy 406.3365 -50.292) (xy 406.3365 -49.784)
				)
			)
		)
	)
	(footprint ""
		(layer "F.Cu")
		(at -2.5146 -126.8222 -90)
		(property "Reference" "R1B11"
			(at 0 0 270)
			(layer "F.SilkS")
			(hide yes)
			(effects
				(font
					(size 1.27 1.27)
				)
			)
		)
		(property "Value" ""
			(at 0 0 270)
			(layer "F.Fab")
			(effects
				(font
					(size 1.27 1.27)
				)
			)
		)
		(duplicate_pad_numbers_are_jumpers no)
		(fp_rect
			(start 0.2794 0.9906)
			(end -0.2794 -0.1016)
			(stroke
				(width 0)
				(type default)
			)
			(fill no)
			(layer "F.CrtYd")
		)
		(fp_line
			(start -0.2794 0.9906)
			(end 0.2794 0.9906)
			(stroke
				(width 0.1)
				(type default)
			)
			(layer "F.Fab")
		)
		(fp_line
			(start 0.2794 0.9906)
			(end 0.2794 -0.1016)
			(stroke
				(width 0.1)
				(type default)
			)
			(layer "F.Fab")
		)
		(fp_line
			(start -0.2794 -0.1016)
			(end -0.2794 0.9906)
			(stroke
				(width 0.1)
				(type default)
			)
			(layer "F.Fab")
		)
		(fp_line
			(start 0.2794 -0.1016)
			(end -0.2794 -0.1016)
			(stroke
				(width 0.1)
				(type default)
			)
			(layer "F.Fab")
		)
		(pad "1" smd rect
			(at 0 0 270)
			(size 0.508 0.508)
			(layers "F.Cu" "F.Mask" "F.Paste")
			(net "SVID_ALERT_PVDDQ_KLM")
		)
		(pad "2" smd rect
			(at 0 0.889 270)
			(size 0.508 0.508)
			(layers "F.Cu" "F.Mask" "F.Paste")
			(net "SVID_ALERT1_CPU1_R_N")
		)
		(zone
			(layer "F.Cu")
			(hatch none 0.5)
			(connect_pads
				(clearance 0)
			)
			(min_thickness 0.25)
			(keepout
				(tracks not_allowed)
				(vias allowed)
				(pads allowed)
				(copperpour not_allowed)
				(footprints allowed)
			)
			(placement
				(enabled no)
				(sheetname "")
			)
			(fill
				(thermal_gap 0.5)
				(thermal_bridge_width 0.5)
				(island_removal_mode 0)
			)
			(polygon
				(pts
					(xy -3.1496 -126.5682) (xy -2.7686 -126.5682) (xy -2.7686 -127.0762) (xy -3.1496 -127.0762)
				)
			)
		)
		(zone
			(layer "F.Cu")
			(hatch none 0.5)
			(connect_pads
				(clearance 0)
			)
			(min_thickness 0.25)
			(keepout
				(tracks allowed)
				(vias not_allowed)
				(pads allowed)
				(copperpour not_allowed)
				(footprints allowed)
			)
			(placement
				(enabled no)
				(sheetname "")
			)
			(fill
				(thermal_gap 0.5)
				(thermal_bridge_width 0.5)
				(island_removal_mode 0)
			)
			(polygon
				(pts
					(xy -3.1496 -126.5682) (xy -2.7686 -126.5682) (xy -2.7686 -127.0762) (xy -3.1496 -127.0762)
				)
			)
		)
	)
	(footprint ""
		(layer "F.Cu")
		(at 192.532 -57.912 90)
		(property "Reference" "RT1"
			(at 1.01473 0.656336 0)
			(unlocked yes)
			(layer "F.SilkS")
			(effects
				(font
					(size 0.4064 0.254)
					(thickness 0.1524)
				)
			)
		)
		(property "Value" ""
			(at 0 0 90)
			(layer "F.Fab")
			(effects
				(font
					(size 1.27 1.27)
				)
			)
		)
		(duplicate_pad_numbers_are_jumpers no)
		(fp_poly
			(pts
				(xy -0.4953 -0.2032) (xy 0.4953 -0.2032) (xy 0.4953 1.6002) (xy -0.4953 1.6002)
			)
			(stroke
				(width 0)
				(type default)
			)
			(fill no)
			(layer "F.CrtYd")
		)
		(fp_line
			(start 0.4953 -0.2032)
			(end 0.4953 1.6002)
			(stroke
				(width 0.1)
				(type default)
			)
			(layer "F.Fab")
		)
		(fp_line
			(start -0.4953 -0.2032)
			(end 0.4953 -0.2032)
			(stroke
				(width 0.1)
				(type default)
			)
			(layer "F.Fab")
		)
		(fp_line
			(start 0.4953 1.6002)
			(end -0.4953 1.6002)
			(stroke
				(width 0.1)
				(type default)
			)
			(layer "F.Fab")
		)
		(fp_line
			(start -0.4953 1.6002)
			(end -0.4953 -0.2032)
			(stroke
				(width 0.1)
				(type default)
			)
			(layer "F.Fab")
		)
		(pad "1" smd rect
			(at 0 0 90)
			(size 0.762 0.889)
			(layers "F.Cu" "F.Mask" "F.Paste")
			(net "VR_PVCCIN_CPU0_PH1_BOOT")
		)
		(pad "2" smd rect
			(at 0 1.397 90)
			(size 0.762 0.889)
			(layers "F.Cu" "F.Mask" "F.Paste")
			(net "VR_PVCCIN_CPU0_PH1_BOOT_R")
		)
		(zone
			(layer "F.Cu")
			(hatch none 0.5)
			(connect_pads
				(clearance 0)
			)
			(min_thickness 0.25)
			(keepout
				(tracks allowed)
				(vias not_allowed)
				(pads allowed)
				(copperpour not_allowed)
				(footprints allowed)
			)
			(placement
				(enabled no)
				(sheetname "")
			)
			(fill
				(thermal_gap 0.5)
				(thermal_bridge_width 0.5)
				(island_removal_mode 0)
			)
			(polygon
				(pts
					(xy 193.4845 -58.293) (xy 192.9765 -58.293) (xy 192.9765 -57.531) (xy 193.4845 -57.531)
				)
			)
		)
		(zone
			(layer "F.Cu")
			(hatch none 0.5)
			(connect_pads
				(clearance 0)
			)
			(min_thickness 0.25)
			(keepout
				(tracks not_allowed)
				(vias allowed)
				(pads allowed)
				(copperpour not_allowed)
				(footprints allowed)
			)
			(placement
				(enabled no)
				(sheetname "")
			)
			(fill
				(thermal_gap 0.5)
				(thermal_bridge_width 0.5)
				(island_removal_mode 0)
			)
			(polygon
				(pts
					(xy 193.4845 -57.531) (xy 193.4845 -58.293) (xy 192.9765 -58.293) (xy 192.9765 -57.531)
				)
			)
		)
	)
	(footprint ""
		(layer "F.Cu")
		(at 362.36656 -142.045182 -90)
		(property "Reference" "RF17"
			(at -0.8382 -0.67818 270)
			(unlocked yes)
			(layer "F.SilkS")
			(effects
				(font
					(size 0.4064 0.254)
					(thickness 0.1524)
				)
				(justify left)
			)
		)
		(property "Value" ""
			(at 0 0 270)
			(layer "F.Fab")
			(effects
				(font
					(size 1.27 1.27)
				)
			)
		)
		(duplicate_pad_numbers_are_jumpers no)
		(fp_poly
			(pts
				(xy -0.2794 -0.1016) (xy 0.2794 -0.1016) (xy 0.2794 0.9906) (xy -0.2794 0.9906)
			)
			(stroke
				(width 0)
				(type default)
			)
			(fill no)
			(layer "F.CrtYd")
		)
		(fp_line
			(start -0.2794 0.9906)
			(end 0.2794 0.9906)
			(stroke
				(width 0.1)
				(type default)
			)
			(layer "F.Fab")
		)
		(fp_line
			(start 0.2794 0.9906)
			(end 0.2794 -0.1016)
			(stroke
				(width 0.1)
				(type default)
			)
			(layer "F.Fab")
		)
		(fp_line
			(start -0.2794 -0.1016)
			(end -0.2794 0.9906)
			(stroke
				(width 0.1)
				(type default)
			)
			(layer "F.Fab")
		)
		(fp_line
			(start 0.2794 -0.1016)
			(end -0.2794 -0.1016)
			(stroke
				(width 0.1)
				(type default)
			)
			(layer "F.Fab")
		)
		(pad "1" smd rect
			(at 0 0 270)
			(size 0.508 0.508)
			(layers "F.Cu" "F.Mask" "F.Paste")
			(net "VR_PVDDQ_DEF_AIREF1")
		)
		(pad "2" smd rect
			(at 0 0.889 270)
			(size 0.508 0.508)
			(layers "F.Cu" "F.Mask" "F.Paste")
			(net "ISENSE_PVDDQ_DEF_PH1_IMON")
		)
		(zone
			(layer "F.Cu")
			(hatch none 0.5)
			(connect_pads
				(clearance 0)
			)
			(min_thickness 0.25)
			(keepout
				(tracks not_allowed)
				(vias allowed)
				(pads allowed)
				(copperpour not_allowed)
				(footprints allowed)
			)
			(placement
				(enabled no)
				(sheetname "")
			)
			(fill
				(thermal_gap 0.5)
				(thermal_bridge_width 0.5)
				(island_removal_mode 0)
			)
			(polygon
				(pts
					(xy 361.73156 -142.299182) (xy 361.73156 -141.791182) (xy 362.11256 -141.791182) (xy 362.11256 -142.299182)
				)
			)
		)
		(zone
			(layer "F.Cu")
			(hatch none 0.5)
			(connect_pads
				(clearance 0)
			)
			(min_thickness 0.25)
			(keepout
				(tracks allowed)
				(vias not_allowed)
				(pads allowed)
				(copperpour not_allowed)
				(footprints allowed)
			)
			(placement
				(enabled no)
				(sheetname "")
			)
			(fill
				(thermal_gap 0.5)
				(thermal_bridge_width 0.5)
				(island_removal_mode 0)
			)
			(polygon
				(pts
					(xy 362.11256 -142.299182) (xy 362.11256 -141.791182) (xy 361.73156 -141.791182) (xy 361.73156 -142.299182)
				)
			)
		)
	)
	(footprint ""
		(layer "F.Cu")
		(at 101.92004 -77.636116)
		(property "Reference" "C2D26"
			(at 0 0 0)
			(layer "F.SilkS")
			(hide yes)
			(effects
				(font
					(size 1.27 1.27)
				)
			)
		)
		(property "Value" ""
			(at 0 0 0)
			(layer "F.Fab")
			(effects
				(font
					(size 1.27 1.27)
				)
			)
		)
		(duplicate_pad_numbers_are_jumpers no)
		(fp_poly
			(pts
				(xy -0.4953 -0.2032) (xy 0.4953 -0.2032) (xy 0.4953 1.6002) (xy -0.4953 1.6002)
			)
			(stroke
				(width 0)
				(type default)
			)
			(fill no)
			(layer "F.CrtYd")
		)
		(fp_line
			(start -0.4953 -0.2032)
			(end 0.4953 -0.2032)
			(stroke
				(width 0.1)
				(type default)
			)
			(layer "F.Fab")
		)
		(fp_line
			(start -0.4953 1.6002)
			(end -0.4953 -0.2032)
			(stroke
				(width 0.1)
				(type default)
			)
			(layer "F.Fab")
		)
		(fp_line
			(start 0.4953 -0.2032)
			(end 0.4953 1.6002)
			(stroke
				(width 0.1)
				(type default)
			)
			(layer "F.Fab")
		)
		(fp_line
			(start 0.4953 1.6002)
			(end -0.4953 1.6002)
			(stroke
				(width 0.1)
				(type default)
			)
			(layer "F.Fab")
		)
		(pad "1" smd rect
			(at 0 0)
			(size 0.762 0.889)
			(layers "F.Cu" "F.Mask" "F.Paste")
			(net "PVCCIN_CPU1")
		)
		(pad "2" smd rect
			(at 0 1.397)
			(size 0.762 0.889)
			(layers "F.Cu" "F.Mask" "F.Paste")
			(net "GND")
		)
		(zone
			(layer "F.Cu")
			(hatch none 0.5)
			(connect_pads
				(clearance 0)
			)
			(min_thickness 0.25)
			(keepout
				(tracks not_allowed)
				(vias allowed)
				(pads allowed)
				(copperpour not_allowed)
				(footprints allowed)
			)
			(placement
				(enabled no)
				(sheetname "")
			)
			(fill
				(thermal_gap 0.5)
				(thermal_bridge_width 0.5)
				(island_removal_mode 0)
			)
			(polygon
				(pts
					(xy 101.53904 -77.191616) (xy 102.30104 -77.191616) (xy 102.30104 -76.683616) (xy 101.53904 -76.683616)
				)
			)
		)
	)
	(footprint ""
		(layer "F.Cu")
		(at 394.72743 -69.65315 90)
		(property "Reference" "C8E6"
			(at 0 0 90)
			(layer "F.SilkS")
			(hide yes)
			(effects
				(font
					(size 1.27 1.27)
				)
			)
		)
		(property "Value" ""
			(at 0 0 90)
			(layer "F.Fab")
			(effects
				(font
					(size 1.27 1.27)
				)
			)
		)
		(duplicate_pad_numbers_are_jumpers no)
		(fp_poly
			(pts
				(xy -0.4953 -0.2032) (xy 0.4953 -0.2032) (xy 0.4953 1.6002) (xy -0.4953 1.6002)
			)
			(stroke
				(width 0)
				(type default)
			)
			(fill no)
			(layer "F.CrtYd")
		)
		(fp_line
			(start 0.4953 -0.2032)
			(end 0.4953 1.6002)
			(stroke
				(width 0.1)
				(type default)
			)
			(layer "F.Fab")
		)
		(fp_line
			(start -0.4953 -0.2032)
			(end 0.4953 -0.2032)
			(stroke
				(width 0.1)
				(type default)
			)
			(layer "F.Fab")
		)
		(fp_line
			(start 0.4953 1.6002)
			(end -0.4953 1.6002)
			(stroke
				(width 0.1)
				(type default)
			)
			(layer "F.Fab")
		)
		(fp_line
			(start -0.4953 1.6002)
			(end -0.4953 -0.2032)
			(stroke
				(width 0.1)
				(type default)
			)
			(layer "F.Fab")
		)
		(pad "1" smd rect
			(at 0 0 90)
			(size 0.762 0.889)
			(layers "F.Cu" "F.Mask" "F.Paste")
			(net "VR_P5V_STBY_BOOT")
		)
		(pad "2" smd rect
			(at 0 1.397 90)
			(size 0.762 0.889)
			(layers "F.Cu" "F.Mask" "F.Paste")
			(net "VR_P5V_STBY_PHASE")
		)
		(zone
			(layer "F.Cu")
			(hatch none 0.5)
			(connect_pads
				(clearance 0)
			)
			(min_thickness 0.25)
			(keepout
				(tracks not_allowed)
				(vias allowed)
				(pads allowed)
				(copperpour not_allowed)
				(footprints allowed)
			)
			(placement
				(enabled no)
				(sheetname "")
			)
			(fill
				(thermal_gap 0.5)
				(thermal_bridge_width 0.5)
				(island_removal_mode 0)
			)
			(polygon
				(pts
					(xy 395.17193 -69.27215) (xy 395.17193 -70.03415) (xy 395.67993 -70.03415) (xy 395.67993 -69.27215)
				)
			)
		)
	)
)
